(kicad_pcb
	(version 20260206)
	(generator "pcbnew")
	(generator_version "10.0")
	(general
		(thickness 1.6)
		(legacy_teardrops no)
	)
	(paper "A4")
	(title_block
		(title "peb — Lightning_PEB_BRD.brd")
		(comment 1 "Lightning (Wiwynn / Facebook NVMe JBOF) / footprints 328-334 of 2563")
	)
	(layers
		(0 "F.Cu" signal "TOP")
		(4 "In1.Cu" signal "L2GND")
		(6 "In2.Cu" signal "L3")
		(8 "In3.Cu" signal "L4VCC")
		(10 "In4.Cu" signal "L5VCC")
		(12 "In5.Cu" signal "L6")
		(14 "In6.Cu" signal "L7GND")
		(2 "B.Cu" signal "BOTTOM")
		(9 "F.Adhes" user "F.Adhesive")
		(11 "B.Adhes" user "B.Adhesive")
		(13 "F.Paste" user "Package Geometry/Pastemask Top")
		(15 "B.Paste" user "Package Geometry/Pastemask Bottom")
		(5 "F.SilkS" user "Ref Des/Silkscreen Top")
		(7 "B.SilkS" user "Ref Des/Silkscreen Bottom")
		(1 "F.Mask" user "Board Geometry/Soldermask Top")
		(3 "B.Mask" user "Board Geometry/Soldermask Bottom")
		(17 "Dwgs.User" user "User.Drawings")
		(19 "Cmts.User" user "User.Comments")
		(21 "Eco1.User" user "User.Eco1")
		(23 "Eco2.User" user "User.Eco2")
		(25 "Edge.Cuts" user "Board Geometry/Outline")
		(27 "Margin" user)
		(31 "F.CrtYd" user "Package Geometry/Place Bound Top")
		(29 "B.CrtYd" user "Package Geometry/Place Bound Bottom")
		(35 "F.Fab" user "Ref Des/Assembly Top")
		(33 "B.Fab" user "Ref Des/Assembly Bottom")
	)
	(footprint ""
		(layer "F.Cu")
		(at 67.794124 -195.681092 180)
		(property "Reference" "C370"
			(at 0 0 180)
			(layer "F.SilkS")
			(hide yes)
			(effects
				(font
					(size 1.27 1.27)
				)
			)
		)
		(property "Value" "SCD1U25V2KX-2-GP"
			(at 1.1811 -2.7051 180)
			(unlocked yes)
			(layer "F.Fab")
			(hide yes)
			(effects
				(font
					(size 1.016 1.016)
					(thickness 0.1524)
				)
			)
		)
		(property "Device Type" "C402H22"
			(at 1.1811 -4.2291 180)
			(unlocked yes)
			(layer "F.Fab")
			(hide yes)
			(effects
				(font
					(size 1.016 1.016)
					(thickness 0.1524)
				)
			)
		)
		(duplicate_pad_numbers_are_jumpers no)
		(fp_rect
			(start -0.4318 0.9525)
			(end 0.4318 -0.9525)
			(stroke
				(width 0)
				(type default)
			)
			(fill no)
			(layer "F.CrtYd")
		)
		(fp_rect
			(start -0.4318 0.9525)
			(end 0.4318 -0.9525)
			(stroke
				(width 0)
				(type default)
			)
			(fill no)
			(layer "F.Fab")
		)
		(pad "1" smd custom
			(at 0 -0.4445 180)
			(size 0.1524 0.1524)
			(layers "F.Cu" "F.Mask" "F.Paste")
			(net "P3V3_STBY")
			(options
				(clearance outline)
				(anchor circle)
			)
			(primitives
				(gr_poly
					(pts
						(arc
							(start 0.3048 -0.2032)
							(mid 0.275042 -0.275042)
							(end 0.2032 -0.3048)
						)
						(arc
							(start -0.2032 -0.3048)
							(mid -0.275042 -0.275042)
							(end -0.3048 -0.2032)
						)
						(arc
							(start -0.3048 0.2032)
							(mid -0.275042 0.275042)
							(end -0.2032 0.3048)
						)
						(arc
							(start 0.2032 0.3048)
							(mid 0.275042 0.275042)
							(end 0.3048 0.2032)
						)
					)
					(width 0)
					(fill yes)
				)
			)
		)
		(pad "2" smd custom
			(at 0 0.4445 180)
			(size 0.1524 0.1524)
			(layers "F.Cu" "F.Mask" "F.Paste")
			(net "GND")
			(options
				(clearance outline)
				(anchor circle)
			)
			(primitives
				(gr_poly
					(pts
						(arc
							(start 0.3048 -0.2032)
							(mid 0.275042 -0.275042)
							(end 0.2032 -0.3048)
						)
						(arc
							(start -0.2032 -0.3048)
							(mid -0.275042 -0.275042)
							(end -0.3048 -0.2032)
						)
						(arc
							(start -0.3048 0.2032)
							(mid -0.275042 0.275042)
							(end -0.2032 0.3048)
						)
						(arc
							(start 0.2032 0.3048)
							(mid 0.275042 0.275042)
							(end 0.3048 0.2032)
						)
					)
					(width 0)
					(fill yes)
				)
			)
		)
	)
	(footprint ""
		(layer "F.Cu")
		(at 135.361934 -74.375518 180)
		(property "Reference" "R447"
			(at 0 0 180)
			(layer "F.SilkS")
			(hide yes)
			(effects
				(font
					(size 1.27 1.27)
				)
			)
		)
		(property "Value" "100KR2F-L1-GP"
			(at 0.064008 -3.993896 180)
			(unlocked yes)
			(layer "F.Fab")
			(hide yes)
			(effects
				(font
					(size 1.016 1.016)
					(thickness 0.1524)
				)
			)
		)
		(property "Device Type" "R402H16"
			(at 0.064008 -5.517896 180)
			(unlocked yes)
			(layer "F.Fab")
			(hide yes)
			(effects
				(font
					(size 1.016 1.016)
					(thickness 0.1524)
				)
			)
		)
		(duplicate_pad_numbers_are_jumpers no)
		(fp_line
			(start 0.508 -0.9398)
			(end -0.508 -0.9398)
			(stroke
				(width 0.1524)
				(type default)
			)
			(layer "F.SilkS")
		)
		(fp_line
			(start -0.508 -0.9398)
			(end -0.508 0.9398)
			(stroke
				(width 0.1524)
				(type default)
			)
			(layer "F.SilkS")
		)
		(fp_rect
			(start -0.508 0.9398)
			(end 0.508 -0.9398)
			(stroke
				(width 0)
				(type default)
			)
			(fill no)
			(layer "F.CrtYd")
		)
		(fp_rect
			(start -0.508 0.9398)
			(end 0.508 -0.9398)
			(stroke
				(width 0)
				(type default)
			)
			(fill no)
			(layer "F.Fab")
		)
		(pad "1" smd custom
			(at 0 -0.4445 180)
			(size 0.1397 0.1397)
			(layers "F.Cu" "F.Mask" "F.Paste")
			(net "SPI_CLK0_R")
			(options
				(clearance outline)
				(anchor circle)
			)
			(primitives
				(gr_poly
					(pts
						(arc
							(start -0.1778 -0.2794)
							(mid -0.249642 -0.249642)
							(end -0.2794 -0.1778)
						)
						(arc
							(start -0.2794 0.1778)
							(mid -0.249642 0.249642)
							(end -0.1778 0.2794)
						)
						(arc
							(start 0.1778 0.2794)
							(mid 0.249642 0.249642)
							(end 0.2794 0.1778)
						)
						(arc
							(start 0.2794 -0.1778)
							(mid 0.249642 -0.249642)
							(end 0.1778 -0.2794)
						)
					)
					(width 0)
					(fill yes)
				)
			)
		)
		(pad "2" smd custom
			(at 0 0.4445 180)
			(size 0.1397 0.1397)
			(layers "F.Cu" "F.Mask" "F.Paste")
			(net "GND")
			(options
				(clearance outline)
				(anchor circle)
			)
			(primitives
				(gr_poly
					(pts
						(arc
							(start -0.1778 -0.2794)
							(mid -0.249642 -0.249642)
							(end -0.2794 -0.1778)
						)
						(arc
							(start -0.2794 0.1778)
							(mid -0.249642 0.249642)
							(end -0.1778 0.2794)
						)
						(arc
							(start 0.1778 0.2794)
							(mid 0.249642 0.249642)
							(end 0.2794 0.1778)
						)
						(arc
							(start 0.2794 -0.1778)
							(mid 0.249642 -0.249642)
							(end 0.1778 -0.2794)
						)
					)
					(width 0)
					(fill yes)
				)
			)
		)
	)
	(footprint ""
		(layer "F.Cu")
		(at 132.056124 -196.443092)
		(property "Reference" "R7959"
			(at 0 0 0)
			(layer "F.SilkS")
			(hide yes)
			(effects
				(font
					(size 1.27 1.27)
				)
			)
		)
		(property "Value" "0R2J-2-GP"
			(at 0.064008 -3.993896 0)
			(unlocked yes)
			(layer "F.Fab")
			(hide yes)
			(effects
				(font
					(size 1.016 1.016)
					(thickness 0.1524)
				)
			)
		)
		(property "Device Type" "R402H16"
			(at 0.064008 -5.517896 0)
			(unlocked yes)
			(layer "F.Fab")
			(hide yes)
			(effects
				(font
					(size 1.016 1.016)
					(thickness 0.1524)
				)
			)
		)
		(duplicate_pad_numbers_are_jumpers no)
		(fp_line
			(start -0.508 -0.9398)
			(end -0.508 0.9398)
			(stroke
				(width 0.1524)
				(type default)
			)
			(layer "F.SilkS")
		)
		(fp_line
			(start 0.508 -0.9398)
			(end -0.508 -0.9398)
			(stroke
				(width 0.1524)
				(type default)
			)
			(layer "F.SilkS")
		)
		(fp_rect
			(start -0.508 0.9398)
			(end 0.508 -0.9398)
			(stroke
				(width 0)
				(type default)
			)
			(fill no)
			(layer "F.CrtYd")
		)
		(fp_rect
			(start -0.508 0.9398)
			(end 0.508 -0.9398)
			(stroke
				(width 0)
				(type default)
			)
			(fill no)
			(layer "F.Fab")
		)
		(pad "1" smd custom
			(at 0 -0.4445)
			(size 0.1397 0.1397)
			(layers "F.Cu" "F.Mask" "F.Paste")
			(net "SSD_PWREN2")
			(options
				(clearance outline)
				(anchor circle)
			)
			(primitives
				(gr_poly
					(pts
						(arc
							(start -0.1778 -0.2794)
							(mid -0.249642 -0.249642)
							(end -0.2794 -0.1778)
						)
						(arc
							(start -0.2794 0.1778)
							(mid -0.249642 0.249642)
							(end -0.1778 0.2794)
						)
						(arc
							(start 0.1778 0.2794)
							(mid 0.249642 0.249642)
							(end 0.2794 0.1778)
						)
						(arc
							(start 0.2794 -0.1778)
							(mid 0.249642 -0.249642)
							(end 0.1778 -0.2794)
						)
					)
					(width 0)
					(fill yes)
				)
			)
		)
		(pad "2" smd custom
			(at 0 0.4445)
			(size 0.1397 0.1397)
			(layers "F.Cu" "F.Mask" "F.Paste")
			(net "SSD_PWREN2_R")
			(options
				(clearance outline)
				(anchor circle)
			)
			(primitives
				(gr_poly
					(pts
						(arc
							(start -0.1778 -0.2794)
							(mid -0.249642 -0.249642)
							(end -0.2794 -0.1778)
						)
						(arc
							(start -0.2794 0.1778)
							(mid -0.249642 0.249642)
							(end -0.1778 0.2794)
						)
						(arc
							(start 0.1778 0.2794)
							(mid 0.249642 0.249642)
							(end 0.2794 0.1778)
						)
						(arc
							(start 0.2794 -0.1778)
							(mid 0.249642 -0.249642)
							(end 0.1778 -0.2794)
						)
					)
					(width 0)
					(fill yes)
				)
			)
		)
	)
	(footprint ""
		(layer "F.Cu")
		(at 27.559 -73.3806 180)
		(property "Reference" "R395"
			(at 0 0 180)
			(layer "F.SilkS")
			(hide yes)
			(effects
				(font
					(size 1.27 1.27)
				)
			)
		)
		(property "Value" "10KR2F-2-GP"
			(at 0.064008 -3.993896 180)
			(unlocked yes)
			(layer "F.Fab")
			(hide yes)
			(effects
				(font
					(size 1.016 1.016)
					(thickness 0.1524)
				)
			)
		)
		(property "Device Type" "R402H16"
			(at 0.064008 -5.517896 180)
			(unlocked yes)
			(layer "F.Fab")
			(hide yes)
			(effects
				(font
					(size 1.016 1.016)
					(thickness 0.1524)
				)
			)
		)
		(duplicate_pad_numbers_are_jumpers no)
		(fp_line
			(start 0.508 -0.9398)
			(end -0.508 -0.9398)
			(stroke
				(width 0.1524)
				(type default)
			)
			(layer "F.SilkS")
		)
		(fp_line
			(start -0.508 -0.9398)
			(end -0.508 0.9398)
			(stroke
				(width 0.1524)
				(type default)
			)
			(layer "F.SilkS")
		)
		(fp_rect
			(start -0.508 0.9398)
			(end 0.508 -0.9398)
			(stroke
				(width 0)
				(type default)
			)
			(fill no)
			(layer "F.CrtYd")
		)
		(fp_rect
			(start -0.508 0.9398)
			(end 0.508 -0.9398)
			(stroke
				(width 0)
				(type default)
			)
			(fill no)
			(layer "F.Fab")
		)
		(pad "1" smd custom
			(at 0 -0.4445 180)
			(size 0.1397 0.1397)
			(layers "F.Cu" "F.Mask" "F.Paste")
			(net "P3V3_STBY")
			(options
				(clearance outline)
				(anchor circle)
			)
			(primitives
				(gr_poly
					(pts
						(arc
							(start -0.1778 -0.2794)
							(mid -0.249642 -0.249642)
							(end -0.2794 -0.1778)
						)
						(arc
							(start -0.2794 0.1778)
							(mid -0.249642 0.249642)
							(end -0.1778 0.2794)
						)
						(arc
							(start 0.1778 0.2794)
							(mid 0.249642 0.249642)
							(end 0.2794 0.1778)
						)
						(arc
							(start 0.2794 -0.1778)
							(mid 0.249642 -0.249642)
							(end 0.1778 -0.2794)
						)
					)
					(width 0)
					(fill yes)
				)
			)
		)
		(pad "2" smd custom
			(at 0 0.4445 180)
			(size 0.1397 0.1397)
			(layers "F.Cu" "F.Mask" "F.Paste")
			(net "RMII_PHY_BMC_RXD1")
			(options
				(clearance outline)
				(anchor circle)
			)
			(primitives
				(gr_poly
					(pts
						(arc
							(start -0.1778 -0.2794)
							(mid -0.249642 -0.249642)
							(end -0.2794 -0.1778)
						)
						(arc
							(start -0.2794 0.1778)
							(mid -0.249642 0.249642)
							(end -0.1778 0.2794)
						)
						(arc
							(start 0.1778 0.2794)
							(mid 0.249642 0.249642)
							(end 0.2794 0.1778)
						)
						(arc
							(start 0.2794 -0.1778)
							(mid 0.249642 -0.249642)
							(end 0.1778 -0.2794)
						)
					)
					(width 0)
					(fill yes)
				)
			)
		)
	)
	(footprint ""
		(layer "F.Cu")
		(at 266.827 -26.289 180)
		(property "Reference" "R766"
			(at 0 0 180)
			(layer "F.SilkS")
			(hide yes)
			(effects
				(font
					(size 1.27 1.27)
				)
			)
		)
		(property "Value" "1KR2F-3-GP"
			(at 0.064008 -3.993896 180)
			(unlocked yes)
			(layer "F.Fab")
			(hide yes)
			(effects
				(font
					(size 1.016 1.016)
					(thickness 0.1524)
				)
			)
		)
		(property "Device Type" "R402H16"
			(at 0.064008 -5.517896 180)
			(unlocked yes)
			(layer "F.Fab")
			(hide yes)
			(effects
				(font
					(size 1.016 1.016)
					(thickness 0.1524)
				)
			)
		)
		(duplicate_pad_numbers_are_jumpers no)
		(fp_line
			(start 0.508 -0.9398)
			(end -0.508 -0.9398)
			(stroke
				(width 0.1524)
				(type default)
			)
			(layer "F.SilkS")
		)
		(fp_line
			(start -0.508 -0.9398)
			(end -0.508 0.9398)
			(stroke
				(width 0.1524)
				(type default)
			)
			(layer "F.SilkS")
		)
		(fp_rect
			(start -0.508 0.9398)
			(end 0.508 -0.9398)
			(stroke
				(width 0)
				(type default)
			)
			(fill no)
			(layer "F.CrtYd")
		)
		(fp_rect
			(start -0.508 0.9398)
			(end 0.508 -0.9398)
			(stroke
				(width 0)
				(type default)
			)
			(fill no)
			(layer "F.Fab")
		)
		(pad "1" smd custom
			(at 0 -0.4445 180)
			(size 0.1397 0.1397)
			(layers "F.Cu" "F.Mask" "F.Paste")
			(net "P3V3_GPIO")
			(options
				(clearance outline)
				(anchor circle)
			)
			(primitives
				(gr_poly
					(pts
						(arc
							(start -0.1778 -0.2794)
							(mid -0.249642 -0.249642)
							(end -0.2794 -0.1778)
						)
						(arc
							(start -0.2794 0.1778)
							(mid -0.249642 0.249642)
							(end -0.1778 0.2794)
						)
						(arc
							(start 0.1778 0.2794)
							(mid 0.249642 0.249642)
							(end 0.2794 0.1778)
						)
						(arc
							(start 0.2794 -0.1778)
							(mid 0.249642 -0.249642)
							(end 0.1778 -0.2794)
						)
					)
					(width 0)
					(fill yes)
				)
			)
		)
		(pad "2" smd custom
			(at 0 0.4445 180)
			(size 0.1397 0.1397)
			(layers "F.Cu" "F.Mask" "F.Paste")
			(net "TWI_SCL1")
			(options
				(clearance outline)
				(anchor circle)
			)
			(primitives
				(gr_poly
					(pts
						(arc
							(start -0.1778 -0.2794)
							(mid -0.249642 -0.249642)
							(end -0.2794 -0.1778)
						)
						(arc
							(start -0.2794 0.1778)
							(mid -0.249642 0.249642)
							(end -0.1778 0.2794)
						)
						(arc
							(start 0.1778 0.2794)
							(mid 0.249642 0.249642)
							(end 0.2794 0.1778)
						)
						(arc
							(start 0.2794 -0.1778)
							(mid 0.249642 -0.249642)
							(end 0.1778 -0.2794)
						)
					)
					(width 0)
					(fill yes)
				)
			)
		)
	)
	(footprint ""
		(layer "F.Cu")
		(at 78.613 -180.9496 -90)
		(property "Reference" "C4108"
			(at 0 0 270)
			(layer "F.SilkS")
			(hide yes)
			(effects
				(font
					(size 1.27 1.27)
				)
			)
		)
		(property "Value" "SCD1U25V3KX-GP"
			(at 0 -2.8194 270)
			(unlocked yes)
			(layer "F.Fab")
			(hide yes)
			(effects
				(font
					(size 1.016 1.016)
					(thickness 0.1524)
				)
			)
		)
		(property "Device Type" "C603H36"
			(at 0 -4.3434 270)
			(unlocked yes)
			(layer "F.Fab")
			(hide yes)
			(effects
				(font
					(size 1.016 1.016)
					(thickness 0.1524)
				)
			)
		)
		(duplicate_pad_numbers_are_jumpers no)
		(fp_line
			(start 0.508 0)
			(end -0.508 0)
			(stroke
				(width 0.2032)
				(type default)
			)
			(layer "F.SilkS")
		)
		(fp_rect
			(start -0.5842 1.3335)
			(end 0.5842 -1.3335)
			(stroke
				(width 0)
				(type default)
			)
			(fill no)
			(layer "F.CrtYd")
		)
		(fp_rect
			(start -0.5842 1.3335)
			(end 0.5842 -1.3335)
			(stroke
				(width 0)
				(type default)
			)
			(fill no)
			(layer "F.Fab")
		)
		(pad "1" smd custom
			(at 0 -0.762 270)
			(size 0.2159 0.2159)
			(layers "F.Cu" "F.Mask" "F.Paste")
			(net "GND")
			(options
				(clearance outline)
				(anchor circle)
			)
			(primitives
				(gr_poly
					(pts
						(arc
							(start -0.3302 -0.4318)
							(mid -0.402042 -0.402042)
							(end -0.4318 -0.3302)
						)
						(arc
							(start -0.4318 0.3302)
							(mid -0.402042 0.402042)
							(end -0.3302 0.4318)
						)
						(arc
							(start 0.3302 0.4318)
							(mid 0.402042 0.402042)
							(end 0.4318 0.3302)
						)
						(arc
							(start 0.4318 -0.3302)
							(mid 0.402042 -0.402042)
							(end 0.3302 -0.4318)
						)
					)
					(width 0)
					(fill yes)
				)
			)
		)
		(pad "2" smd custom
			(at 0 0.762 270)
			(size 0.2159 0.2159)
			(layers "F.Cu" "F.Mask" "F.Paste")
			(net "SSD_PWREN5_R")
			(options
				(clearance outline)
				(anchor circle)
			)
			(primitives
				(gr_poly
					(pts
						(arc
							(start -0.3302 -0.4318)
							(mid -0.402042 -0.402042)
							(end -0.4318 -0.3302)
						)
						(arc
							(start -0.4318 0.3302)
							(mid -0.402042 0.402042)
							(end -0.3302 0.4318)
						)
						(arc
							(start 0.3302 0.4318)
							(mid 0.402042 0.402042)
							(end 0.4318 0.3302)
						)
						(arc
							(start 0.4318 -0.3302)
							(mid 0.402042 -0.402042)
							(end 0.3302 -0.4318)
						)
					)
					(width 0)
					(fill yes)
				)
			)
		)
	)
	(footprint ""
		(layer "F.Cu")
		(at 143.898874 -97.55632 90)
		(property "Reference" "PR77"
			(at 0 0 90)
			(layer "F.SilkS")
			(hide yes)
			(effects
				(font
					(size 1.27 1.27)
				)
			)
		)
		(property "Value" "0R3J-0-U-GP"
			(at -0.0254 -2.5146 90)
			(unlocked yes)
			(layer "F.Fab")
			(hide yes)
			(effects
				(font
					(size 1.016 1.016)
					(thickness 0.1524)
				)
			)
		)
		(property "Device Type" "R603H22"
			(at -0.0254 -4.0386 90)
			(unlocked yes)
			(layer "F.Fab")
			(hide yes)
			(effects
				(font
					(size 1.016 1.016)
					(thickness 0.1524)
				)
			)
		)
		(duplicate_pad_numbers_are_jumpers no)
		(fp_line
			(start 0.2032 0)
			(end 0.4826 0)
			(stroke
				(width 0.2032)
				(type default)
			)
			(layer "F.SilkS")
		)
		(fp_line
			(start -0.4826 0)
			(end -0.2032 0)
			(stroke
				(width 0.2032)
				(type default)
			)
			(layer "F.SilkS")
		)
		(fp_rect
			(start -0.5842 1.3335)
			(end 0.5842 -1.3335)
			(stroke
				(width 0)
				(type default)
			)
			(fill no)
			(layer "F.CrtYd")
		)
		(fp_rect
			(start -0.5842 1.3335)
			(end 0.5842 -1.3335)
			(stroke
				(width 0)
				(type default)
			)
			(fill no)
			(layer "F.Fab")
		)
		(pad "1" smd custom
			(at 0 -0.762 90)
			(size 0.2159 0.2159)
			(layers "F.Cu" "F.Mask" "F.Paste")
			(net "P3V3_STBY")
			(options
				(clearance outline)
				(anchor circle)
			)
			(primitives
				(gr_poly
					(pts
						(arc
							(start -0.3302 -0.4318)
							(mid -0.402042 -0.402042)
							(end -0.4318 -0.3302)
						)
						(arc
							(start -0.4318 0.3302)
							(mid -0.402042 0.402042)
							(end -0.3302 0.4318)
						)
						(arc
							(start 0.3302 0.4318)
							(mid 0.402042 0.402042)
							(end 0.4318 0.3302)
						)
						(arc
							(start 0.4318 -0.3302)
							(mid 0.402042 -0.402042)
							(end 0.3302 -0.4318)
						)
					)
					(width 0)
					(fill yes)
				)
			)
		)
		(pad "2" smd custom
			(at 0 0.762 90)
			(size 0.2159 0.2159)
			(layers "F.Cu" "F.Mask" "F.Paste")
			(net "VR_P1V8_STBY_IN")
			(options
				(clearance outline)
				(anchor circle)
			)
			(primitives
				(gr_poly
					(pts
						(arc
							(start -0.3302 -0.4318)
							(mid -0.402042 -0.402042)
							(end -0.4318 -0.3302)
						)
						(arc
							(start -0.4318 0.3302)
							(mid -0.402042 0.402042)
							(end -0.3302 0.4318)
						)
						(arc
							(start 0.3302 0.4318)
							(mid 0.402042 0.402042)
							(end 0.4318 0.3302)
						)
						(arc
							(start 0.4318 -0.3302)
							(mid 0.402042 -0.402042)
							(end 0.3302 -0.4318)
						)
					)
					(width 0)
					(fill yes)
				)
			)
		)
	)
)
